FILE_TYPE=LIBRARY_PARTS;
primitive 'LM4040AIM3X25NOPB';
  pin
    '1+':
      PIN_NUMBER='(1)';
      BIDIRECTIONAL='TRUE';
      INPUT_LOAD='(-0.01,0.01)';
      OUTPUT_LOAD='(1.0,-1.0)';
    '2-':
      PIN_NUMBER='(2)';
      OUTPUT_LOAD='(1.0,-1.0)';
    '3':
      PIN_NUMBER='(3)';
      BIDIRECTIONAL='TRUE';
      INPUT_LOAD='(-0.01,0.01)';
      OUTPUT_LOAD='(1.0,-1.0)';
  end_pin;
  body
    PART_NAME='LM4040AIM3X25NOPB';
    BODY_NAME='LM4040AIM3X25NOPB';
    PHYS_DES_PREFIX='U';
    CLASS='IC';
  end_body;
end_primitive;

END.
